# TIMECARD (Time Appliance Project (Time Card)) — schematic netlist excerpt (pin names and nets, part order shuffled) for the footprints in the layout excerpt that follows; sources: Cadence DE-HDL packaged netlist, KiCad conversion of R4006-B0001-02_R01.brd

R372  RESISTOR  49.9OHM 1%  pkg SMC_0402R_H016  page 23 : \1\ = BF_ANT2_IN ; \2\ = ANT2_IN
C256  CAPACITOR  0.1UF 10V 10%  pkg SMC_0402R_H022  page 29 : \1\ = UNNAMED_523_CAPACITOR_I7_1 ; \2\ = SG

(kicad_pcb
	(version 20260206)
	(generator "pcbnew")
	(generator_version "10.0")
	(general
		(thickness 1.6)
		(legacy_teardrops no)
	)
	(paper "A4")
	(title_block
		(title "timecard-production-celestica-r4006 — R4006-B0001-02_R01.brd")
		(comment 1 "Time Appliance Project (Time Card) / footprints 423-424 of 1113")
	)
	(layers
		(0 "F.Cu" signal "TOP")
		(4 "In1.Cu" signal "L02_GND1")
		(6 "In2.Cu" signal "L03_SIG1")
		(8 "In3.Cu" signal "L04_GND2")
		(10 "In4.Cu" signal "L05_VCC1")
		(12 "In5.Cu" signal "L06_VCC2")
		(14 "In6.Cu" signal "L07_GND3")
		(16 "In7.Cu" signal "L08_SIG2")
		(18 "In8.Cu" signal "L09_GND4")
		(2 "B.Cu" signal "BOTTOM")
		(9 "F.Adhes" user "F.Adhesive")
		(11 "B.Adhes" user "B.Adhesive")
		(13 "F.Paste" user "Package Geometry/Pastemask Top")
		(15 "B.Paste" user "Package Geometry/Pastemask Bottom")
		(5 "F.SilkS" user "Ref Des/Silkscreen Top")
		(7 "B.SilkS" user "Ref Des/Silkscreen Bottom")
		(1 "F.Mask" user "Board Geometry/Soldermask Top")
		(3 "B.Mask" user "Board Geometry/Soldermask Bottom")
		(17 "Dwgs.User" user "User.Drawings")
		(19 "Cmts.User" user "User.Comments")
		(21 "Eco1.User" user "User.Eco1")
		(23 "Eco2.User" user "User.Eco2")
		(25 "Edge.Cuts" user "Board Geometry/Outline")
		(27 "Margin" user)
		(31 "F.CrtYd" user "Package Geometry/Place Bound Top")
		(29 "B.CrtYd" user "Package Geometry/Place Bound Bottom")
		(35 "F.Fab" user "Ref Des/Assembly Top")
		(33 "B.Fab" user "Ref Des/Assembly Bottom")
	)
	(footprint ""
		(layer "F.Cu")
		(at 12.192 -52.578 90)
		(property "Reference" "R372"
			(at -0.508 -3.13563 90)
			(unlocked yes)
			(layer "F.SilkS")
			(effects
				(font
					(size 0.7874 0.5842)
					(thickness 0.1524)
				)
			)
		)
		(property "Value" "VAL*"
			(at 0.02032 2.13233 90)
			(unlocked yes)
			(layer "F.Fab")
			(hide yes)
			(effects
				(font
					(size 0.7874 0.5842)
					(thickness 0.1524)
				)
			)
		)
		(property "Tolerance" "TOL*"
			(at 0.044704 3.05435 90)
			(unlocked yes)
			(layer "Cmts.User")
			(hide yes)
			(effects
				(font
					(size 0.7874 0.5842)
					(thickness 0.1524)
				)
			)
		)
		(property "User Part Number" "PARTNUM*"
			(at 0.02032 4.024884 90)
			(unlocked yes)
			(layer "Cmts.User")
			(hide yes)
			(effects
				(font
					(size 0.7874 0.5842)
					(thickness 0.1524)
				)
			)
		)
		(property "Device Type" "RESISTOR-G155-149R9-01,49.9OHMA"
			(at 0.008382 1.210564 90)
			(unlocked yes)
			(layer "F.Fab")
			(hide yes)
			(effects
				(font
					(size 0.7874 0.5842)
					(thickness 0.1524)
				)
			)
		)
		(duplicate_pad_numbers_are_jumpers no)
		(fp_line
			(start 1.143 -0.5588)
			(end -1.143 -0.5588)
			(stroke
				(width 0.1)
				(type default)
			)
			(layer "F.SilkS")
		)
		(fp_line
			(start -1.143 -0.5588)
			(end -1.143 0.5588)
			(stroke
				(width 0.1)
				(type default)
			)
			(layer "F.SilkS")
		)
		(fp_line
			(start 1.143 0.5588)
			(end 1.143 -0.5588)
			(stroke
				(width 0.1)
				(type default)
			)
			(layer "F.SilkS")
		)
		(fp_line
			(start -1.143 0.5588)
			(end 1.143 0.5588)
			(stroke
				(width 0.1)
				(type default)
			)
			(layer "F.SilkS")
		)
		(fp_poly
			(pts
				(xy -1.143 0.5588) (xy 1.143 0.5588) (xy 1.143 -0.5588) (xy -1.143 -0.5588)
			)
			(stroke
				(width 0)
				(type default)
			)
			(fill no)
			(layer "F.CrtYd")
		)
		(fp_line
			(start 0.508 -0.3048)
			(end -0.508 -0.3048)
			(stroke
				(width 0.1)
				(type default)
			)
			(layer "F.Fab")
		)
		(fp_line
			(start -0.508 -0.3048)
			(end -0.508 0.3048)
			(stroke
				(width 0.1)
				(type default)
			)
			(layer "F.Fab")
		)
		(fp_line
			(start 0.508 0.3048)
			(end 0.508 -0.3048)
			(stroke
				(width 0.1)
				(type default)
			)
			(layer "F.Fab")
		)
		(fp_line
			(start -0.508 0.3048)
			(end 0.508 0.3048)
			(stroke
				(width 0.1)
				(type default)
			)
			(layer "F.Fab")
		)
		(pad "1" smd rect
			(at -0.5334 0 90)
			(size 0.7112 0.6096)
			(layers "F.Cu" "F.Mask" "F.Paste")
			(net "BF_ANT2_IN")
		)
		(pad "2" smd rect
			(at 0.5334 0 90)
			(size 0.7112 0.6096)
			(layers "F.Cu" "F.Mask" "F.Paste")
			(net "ANT2_IN")
		)
		(zone
			(layer "F.Cu")
			(hatch none 0.5)
			(connect_pads
				(clearance 0)
			)
			(min_thickness 0.25)
			(keepout
				(tracks allowed)
				(vias not_allowed)
				(pads allowed)
				(copperpour not_allowed)
				(footprints allowed)
			)
			(placement
				(enabled no)
				(sheetname "")
			)
			(fill
				(thermal_gap 0.5)
				(thermal_bridge_width 0.5)
				(island_removal_mode 0)
			)
			(polygon
				(pts
					(xy 12.4968 -52.5018) (xy 12.4968 -52.6542) (xy 11.8872 -52.6542) (xy 11.8872 -52.5018)
				)
			)
		)
		(zone
			(layer "F.Cu")
			(hatch none 0.5)
			(connect_pads
				(clearance 0)
			)
			(min_thickness 0.25)
			(keepout
				(tracks not_allowed)
				(vias allowed)
				(pads allowed)
				(copperpour not_allowed)
				(footprints allowed)
			)
			(placement
				(enabled no)
				(sheetname "")
			)
			(fill
				(thermal_gap 0.5)
				(thermal_bridge_width 0.5)
				(island_removal_mode 0)
			)
			(polygon
				(pts
					(xy 12.4968 -52.5018) (xy 12.4968 -52.6542) (xy 11.8872 -52.6542) (xy 11.8872 -52.5018)
				)
			)
		)
	)
	(footprint ""
		(layer "F.Cu")
		(at 141.097 -59.563 90)
		(property "Reference" "C256"
			(at 3.048 -1.73863 90)
			(unlocked yes)
			(layer "F.SilkS")
			(effects
				(font
					(size 0.7874 0.5842)
					(thickness 0.1524)
				)
			)
		)
		(property "Value" "VAL*"
			(at 0.0762 2.067306 90)
			(unlocked yes)
			(layer "F.Fab")
			(hide yes)
			(effects
				(font
					(size 0.7874 0.5842)
					(thickness 0.1524)
				)
			)
		)
		(property "Device Type" "CAPACITOR-G105-0B104-CK,0.1UF,A"
			(at 0.0508 1.127506 90)
			(unlocked yes)
			(layer "F.Fab")
			(hide yes)
			(effects
				(font
					(size 0.7874 0.5842)
					(thickness 0.1524)
				)
			)
		)
		(property "User Part Number" "PARTNUM*"
			(at 0.1016 4.023106 90)
			(unlocked yes)
			(layer "Cmts.User")
			(hide yes)
			(effects
				(font
					(size 0.7874 0.5842)
					(thickness 0.1524)
				)
			)
		)
		(property "Tolerance" "TOL*"
			(at 0.0762 3.032506 90)
			(unlocked yes)
			(layer "Cmts.User")
			(hide yes)
			(effects
				(font
					(size 0.7874 0.5842)
					(thickness 0.1524)
				)
			)
		)
		(duplicate_pad_numbers_are_jumpers no)
		(fp_line
			(start 1.143 -0.5588)
			(end -1.143 -0.5588)
			(stroke
				(width 0.1)
				(type default)
			)
			(layer "F.SilkS")
		)
		(fp_line
			(start -1.143 -0.5588)
			(end -1.143 0.5588)
			(stroke
				(width 0.1)
				(type default)
			)
			(layer "F.SilkS")
		)
		(fp_line
			(start 1.143 0.5588)
			(end 1.143 -0.5588)
			(stroke
				(width 0.1)
				(type default)
			)
			(layer "F.SilkS")
		)
		(fp_line
			(start -1.143 0.5588)
			(end 1.143 0.5588)
			(stroke
				(width 0.1)
				(type default)
			)
			(layer "F.SilkS")
		)
		(fp_rect
			(start -1.143 -0.5588)
			(end 1.143 0.5588)
			(stroke
				(width 0)
				(type default)
			)
			(fill no)
			(layer "F.CrtYd")
		)
		(fp_line
			(start 0.508 -0.3048)
			(end -0.508 -0.3048)
			(stroke
				(width 0.1)
				(type default)
			)
			(layer "F.Fab")
		)
		(fp_line
			(start -0.508 -0.3048)
			(end -0.508 0.3048)
			(stroke
				(width 0.1)
				(type default)
			)
			(layer "F.Fab")
		)
		(fp_line
			(start 0.508 0.3048)
			(end 0.508 -0.3048)
			(stroke
				(width 0.1)
				(type default)
			)
			(layer "F.Fab")
		)
		(fp_line
			(start -0.508 0.3048)
			(end 0.508 0.3048)
			(stroke
				(width 0.1)
				(type default)
			)
			(layer "F.Fab")
		)
		(pad "1" smd rect
			(at -0.5334 0 90)
			(size 0.7112 0.6096)
			(layers "F.Cu" "F.Mask" "F.Paste")
			(net "UNNAMED_523_CAPACITOR_I7_1")
		)
		(pad "2" smd rect
			(at 0.5334 0 90)
			(size 0.7112 0.6096)
			(layers "F.Cu" "F.Mask" "F.Paste")
			(net "SG")
		)
		(zone
			(layer "F.Cu")
			(hatch none 0.5)
			(connect_pads
				(clearance 0)
			)
			(min_thickness 0.25)
			(keepout
				(tracks allowed)
				(vias not_allowed)
				(pads allowed)
				(copperpour not_allowed)
				(footprints allowed)
			)
			(placement
				(enabled no)
				(sheetname "")
			)
			(fill
				(thermal_gap 0.5)
				(thermal_bridge_width 0.5)
				(island_removal_mode 0)
			)
			(polygon
				(pts
					(xy 140.7922 -59.4868) (xy 141.4018 -59.4868) (xy 141.4018 -59.6392) (xy 140.7922 -59.6392)
				)
			)
		)
	)
)
